FILE_TYPE = CONNECTIVITY;
{Allegro Design Entry HDL 17.2-2016 S081 (4005846) 1/11/2022}
"PAGE_NUMBER" = 83;
0"NC";
1"P1V8_STBY\g";
2"P3V3_STBY\g";
3"P3V3_STBY\g";
4"P3V3_STBY\g";
5"P3V3_STBY\g";
6"P12V_STBY\g";
7"GND\g";
8"P1V8_STBY\g";
9"P12V_STBY\g";
10"GND\g";
11"GND\g";
12"GND\g";
13"GND\g";
14"GND\g";
15"GND\g";
16"P3V3_STBY\g";
17"P3V3_STBY\g";
18"P3V3_STBY\g";
19"GND\g";
20"GND\g";
21"GND\g";
22"GND\g";
23"GND\g";
24"GND\g";
25"GND\g";
26"SCM_PRSNT0_N";
27"SCM_PRSNT0_R";
28"P3V3_STBY\g";
29"P3V3_STBY\g";
30"GND\g";
31"GND\g";
32"P1V8_STBY\g";
33"P1V8_STBY\g";
34"FAN_DR_FAIL_N";
35"FAN_SR_FAIL_N";
36"FPGA_RDY_N";
37"FM_CLK_BUFFER_EN";
38"FM_FAN_DR_FAIL_R_N";
39"FM_FAN_SR_FAIL_R_N";
40"FM_CLK_BUFFER_BUF_EN";
41"FM_FAN_SR_FAIL_N";
42"FM_FAN_DR_FAIL_N";
43"FM_CLK_BUFFER0_EN";
44"FM_CLK_BUFFER1_EN";
45"FM_CLK_BUFFER2_EN";
46"FM_CLK_BUFFER4_EN";
47"FM_CLK_BUFFER3_EN";
48"SCM_IRQ_1V8_N";
49"FPGA_RDY";
50"FPGA_RDY_R_N";
51"FPGA_RDY_N";
52"SCM_IRQ_R_N";
53"HPM_STBY_RDY";
54"SCM_IRQ_N";
55"FM_FAN_DR_FULL_SPEED";
56"FAN_DR_FULL_SPEED_N";
57"FM_FAN_SR_FULL_SPEED";
58"FAN_SR_FULL_SPEED_N";
59"FAN_DR_FULL_SPEED_N_R";
60"FAN_SR_FULL_SPEED_N_R";
61"SCM_PRSNT0";
%"Q_RES"
"1","(-6025,2975)","0","pure_quanta","I100";
;
LOCATION"R1398"
$SEC"1"
CDS_SEC"1"
VALUE"0"
PACK_TYPE"0402LF"
PART_NUMBER"CS00002JB38"
TOLERANCE"5%"
MATERIAL"CHIP"
WATTAGE"1/16W"
CDS_LIB"pure_quanta"
BOM_COST"OCP3.0 ";
"B"
$PN"2"43;
"A"
$PN"1"40;
%"UNIVERSAL_POWER"
"1","(-6450,2050)","0","pure_quanta_power","I17";
;
HDL_POWER"P1V8_STBY"
CDS_LIB"pure_quanta_power"
BOM_COST"OCP3.0 ";
"A"1;
%"Q_RES"
"2","(-6450,1775)","0","pure_quanta","I18";
;
LOCATION"R735"
$SEC"1"
CDS_SEC"1"
PACK_TYPE"0402LF"
PART_NUMBER"TMP_QCS24702JB38"
VALUE"4.7K"
TOLERANCE"5%"
MATERIAL"CHIP"
WATTAGE"1/16W"
BOM_COST"OCP3.0 "
CDS_LIB"pure_quanta";
"A"
$PN"1"1;
"B"
$PN"2"39;
%"Q_RES"
"2","(-8275,1750)","0","pure_quanta","I181";
;
LOCATION"R1445"
$SEC"1"
CDS_SEC"1"
VALUE"4.7K"
PACK_TYPE"0402LF"
PART_NUMBER"TMP_QCS24702JB38"
TOLERANCE"5%"
MATERIAL"CHIP"
WATTAGE"1/16W"
BOM_COST"OCP3.0 "
CDS_LIB"pure_quanta";
"A"
$PN"1"2;
"B"
$PN"2"35;
%"UNIVERSAL_POWER"
"1","(-8275,1950)","0","pure_quanta_power","I182";
;
HDL_POWER"P3V3_STBY"
CDS_LIB"pure_quanta_power"
BOM_COST"OCP3.0 ";
"A"2;
%"UNIVERSAL_POWER"
"1","(-8250,1125)","0","pure_quanta_power","I183";
;
HDL_POWER"P3V3_STBY"
BOM_COST"OCP3.0 "
CDS_LIB"pure_quanta_power";
"A"3;
%"Q_RES"
"2","(-8250,925)","0","pure_quanta","I184";
;
LOCATION"R1446"
$SEC"1"
CDS_SEC"1"
VALUE"4.7K"
PACK_TYPE"0402LF"
PART_NUMBER"TMP_QCS24702JB38"
TOLERANCE"5%"
MATERIAL"CHIP"
WATTAGE"1/16W"
CDS_LIB"pure_quanta"
BOM_COST"OCP3.0 ";
"A"
$PN"1"3;
"B"
$PN"2"34;
%"UNIVERSAL_POWER"
"1","(-2950,1800)","0","pure_quanta_power","I185";
;
HDL_POWER"P3V3_STBY"
CDS_LIB"pure_quanta_power";
"A"4;
%"UNIVERSAL_POWER"
"1","(-5850,4825)","0","pure_quanta_power","I186";
;
HDL_POWER"P3V3_STBY"
BOM_COST"OCP3.0 "
CDS_LIB"pure_quanta_power";
"A"5;
%"Q_RES"
"2","(-5850,4550)","0","pure_quanta","I188";
;
LOCATION"R1338"
$SEC"1"
CDS_SEC"1"
PACK_TYPE"0402LF"
PART_NUMBER"TMP_QCS24702JB38"
VALUE"4.7K"
TOLERANCE"5%"
MATERIAL"CHIP"
WATTAGE"1/16W"
BOM_COST"OCP3.0 "
CDS_LIB"pure_quanta";
"A"
$PN"1"5;
"B"
$PN"2"54;
%"Q_RES"
"1","(-6425,4300)","0","pure_quanta","I189";
;
LOCATION"R71"
$SEC"1"
CDS_SEC"1"
VALUE"33"
ROOM"RST_CPU0_PLD_TO_DIMM"
PACK_TYPE"0402LF"
PART_NUMBER"CS03302JB29"
TOLERANCE"5%"
MATERIAL"CHIP"
WATTAGE"1/16W"
BOM_COST"MEM"
CDS_LIB"pure_quanta";
"B"
$PN"2"54;
"A"
$PN"1"52;
%"Q_RES"
"1","(-5950,1525)","0","pure_quanta","I19";
;
LOCATION"R1355"
$SEC"1"
CDS_SEC"1"
VALUE"33"
MATERIAL"CHIP"
PACK_TYPE"0402LF"
PART_NUMBER"CS03302JB29"
TOLERANCE"5%"
WATTAGE"1/16W"
BOM_COST"OCP3.0 "
CDS_LIB"pure_quanta";
"B"
$PN"2"41;
"A"
$PN"1"39;
%"Q_RES"
"1","(-2000,1350)","0","pure_quanta","I190";
;
LOCATION"R1391"
$SEC"1"
CDS_SEC"1"
VALUE"33"
PACK_TYPE"0402LF"
PART_NUMBER"CS03302JB29"
TOLERANCE"5%"
MATERIAL"CHIP"
WATTAGE"1/16W"
CDS_LIB"pure_quanta";
"B"
$PN"2"59;
"A"
$PN"1"56;
%"Q_RES"
"1","(-1975,2750)","0","pure_quanta","I191";
;
LOCATION"R1387"
$SEC"1"
CDS_SEC"1"
VALUE"33"
PACK_TYPE"0402LF"
PART_NUMBER"CS03302JB29"
TOLERANCE"5%"
MATERIAL"CHIP"
WATTAGE"1/16W"
CDS_LIB"pure_quanta";
"B"
$PN"2"60;
"A"
$PN"1"58;
%"Q_RES"
"1","(-2100,4300)","0","pure_quanta","I195";
;
LOCATION"R1426"
$SEC"1"
CDS_SEC"1"
VALUE"33"
PACK_TYPE"0402LF"
PART_NUMBER"CS03302JB29"
TOLERANCE"5%"
MATERIAL"CHIP"
WATTAGE"1/16W"
CDS_LIB"pure_quanta";
"B"
$PN"2"61;
"A"
$PN"1"27;
%"UNIVERSAL_POWER"
"1","(-2975,4800)","0","pure_quanta_power","I196";
;
HDL_POWER"P12V_STBY"
BOM_COST"OCP3.0 "
CDS_LIB"pure_quanta_power";
"A"6;
%"Q_RES"
"2","(-2975,4600)","0","pure_quanta","I197";
;
LOCATION"R887"
$SEC"1"
CDS_SEC"1"
VALUE"10K"
TOLERANCE"5%"
WATTAGE"1/16W"
MATERIAL"CHIP"
PART_NUMBER"TMP_QCS31002JB28"
PACK_TYPE"0402LF"
CDS_LIB"pure_quanta"
BOM_COST"OCP3.0 ";
"A"
$PN"1"6;
"B"
$PN"2"27;
%"MOSFET_N"
"1","(-3025,4150)","0","pure_quanta","I198";
;
LOCATION"U76"
$SEC"1"
CDS_SEC"1"
VALUE"BSS138K"
MATERIAL"IC"
PART_NUMBER"BAM138K0000"
PACK_TYPE"SMLF"
CDS_LIB"pure_quanta"
CDS_LMAN_SYM_OUTLINE"-50,50,100,-150"
MANUF_PN"BSS138K";
"GATE"
$PN"G"26;
"SOURCE"
$PN"S"7;
"DRAIN"
$PN"D"27;
%"UNIVERSAL_GND"
"1","(-2975,3825)","0","pure_quanta_power","I199";
;
CDS_LIB"pure_quanta_power"
HDL_POWER"GND";
"A"7;
%"UNIVERSAL_POWER"
"1","(-6450,1225)","0","pure_quanta_power","I20";
;
HDL_POWER"P1V8_STBY"
CDS_LIB"pure_quanta_power"
BOM_COST"OCP3.0 ";
"A"8;
%"UNIVERSAL_POWER"
"1","(-3550,4525)","0","pure_quanta_power","I200";
;
HDL_POWER"P12V_STBY"
CDS_LIB"pure_quanta_power"
BOM_COST"OCP3.0 ";
"A"9;
%"Q_RES"
"2","(-3550,4300)","0","pure_quanta","I201";
;
LOCATION"R886"
$SEC"1"
CDS_SEC"1"
MATERIAL"CHIP"
WATTAGE"1/16W"
TOLERANCE"5%"
VALUE"10K"
PACK_TYPE"0402LF"
PART_NUMBER"TMP_QCS31002JB28"
BOM_COST"OCP3.0 "
CDS_LIB"pure_quanta";
"A"
$PN"1"9;
"B"
$PN"2"26;
%"Q_RES"
"2","(-3550,3800)","0","pure_quanta","I203";
;
LOCATION"R5022"
$SEC"1"
CDS_SEC"1"
PACK_TYPE"0402LF"
MATERIAL"CHIP"
PART_NUMBER"CS23832FB01"
WATTAGE"1/16W"
TOLERANCE"1%"
VALUE"3.83K"
CDS_LIB"pure_quanta"
BOM_COST"OCP3.0 ";
"A"
$PN"1"26;
"B"
$PN"2"10;
%"UNIVERSAL_GND"
"1","(-3550,3500)","0","pure_quanta_power","I204";
;
CDS_LIB"pure_quanta_power"
HDL_POWER"GND";
"A"10;
%"Q_RES"
"2","(-2475,4050)","0","pure_quanta","I205";
;
LOCATION"R5023"
$SEC"1"
CDS_SEC"1"
TOLERANCE"1%"
VALUE"3.83K"
PART_NUMBER"CS23832FB01"
WATTAGE"1/16W"
MATERIAL"CHIP"
PACK_TYPE"0402LF"
BOM_COST"OCP3.0 "
CDS_LIB"pure_quanta";
"A"
$PN"1"27;
"B"
$PN"2"11;
%"UNIVERSAL_GND"
"1","(-2475,3750)","0","pure_quanta_power","I206";
;
HDL_POWER"GND"
CDS_LIB"pure_quanta_power";
"A"11;
%"Q_RES"
"2","(-6450,950)","0","pure_quanta","I21";
;
LOCATION"R1197"
$SEC"1"
CDS_SEC"1"
PACK_TYPE"0402LF"
PART_NUMBER"TMP_QCS24702JB38"
VALUE"4.7K"
TOLERANCE"5%"
MATERIAL"CHIP"
WATTAGE"1/16W"
BOM_COST"OCP3.0 "
CDS_LIB"pure_quanta";
"A"
$PN"1"8;
"B"
$PN"2"38;
%"Q_RES"
"1","(-5925,700)","0","pure_quanta","I22";
;
LOCATION"R1365"
$SEC"1"
CDS_SEC"1"
VALUE"33"
MATERIAL"CHIP"
PACK_TYPE"0402LF"
PART_NUMBER"CS03302JB29"
TOLERANCE"5%"
WATTAGE"1/16W"
CDS_LIB"pure_quanta"
BOM_COST"OCP3.0 ";
"B"
$PN"2"42;
"A"
$PN"1"38;
%"SN74LVC1G07DBVR"
"1","(-7250,1525)","0","pure_quanta","I23";
;
LOCATION"U111"
$SEC"1"
CDS_SEC"1"
PACK_TYPE"SMLF"
PART_NUMBER"AL1G0007024"
VALUE"SN74LVC1G07DBVR"
MATERIAL"IC"
CDS_LIB"pure_quanta"
NEEDS_NO_SIZE"TRUE";
"NC"
$PN"1"0;
"Y"
$PN"4"39;
"GND"
$PN"3"12;
"A"
$PN"2"35;
"VCC"
$PN"5"28;
%"UNIVERSAL_GND"
"1","(-7550,1225)","0","pure_quanta_power","I24";
;
HDL_POWER"GND"
BOM_COST"OCP3.0 "
CDS_LIB"pure_quanta_power";
"A"12;
%"SN74LVC1G07DBVR"
"1","(-7250,700)","0","pure_quanta","I25";
;
LOCATION"U112"
$SEC"1"
CDS_SEC"1"
PACK_TYPE"SMLF"
PART_NUMBER"AL1G0007024"
VALUE"SN74LVC1G07DBVR"
MATERIAL"IC"
CDS_LIB"pure_quanta"
NEEDS_NO_SIZE"TRUE";
"NC"
$PN"1"0;
"Y"
$PN"4"38;
"GND"
$PN"3"15;
"A"
$PN"2"34;
"VCC"
$PN"5"29;
%"UNIVERSAL_POWER"
"1","(-7900,2025)","0","pure_quanta_power","I26";
;
HDL_POWER"P3V3_STBY"
BOM_COST"OCP3.0 "
CDS_LIB"pure_quanta_power";
"A"28;
%"UNIVERSAL_GND"
"1","(-7900,1575)","0","pure_quanta_power","I27";
;
HDL_POWER"GND"
CDS_LIB"pure_quanta_power"
BOM_COST"OCP3.0 ";
"A"13;
%"Q_CAP"
"1","(-7900,1775)","0","pure_quanta","I28";
;
LOCATION"C584"
$SEC"1"
CDS_SEC"1"
PACK_TYPE"0402"
VOLTAGE"25V"
PART_NUMBER"CH4104K1B00"
VALUE"0.1UF"
TOLERANCE"10%"
MATERIAL"X7R"
BOM_COST"OCP3.0 "
CDS_LIB"pure_quanta";
"B"
$PN"2"13;
"A"
$PN"1"28;
%"UNIVERSAL_POWER"
"1","(-7900,1200)","0","pure_quanta_power","I30";
;
HDL_POWER"P3V3_STBY"
CDS_LIB"pure_quanta_power"
BOM_COST"OCP3.0 ";
"A"29;
%"Q_CAP"
"1","(-7900,950)","0","pure_quanta","I31";
;
LOCATION"C667"
$SEC"1"
CDS_SEC"1"
PACK_TYPE"0402"
VOLTAGE"25V"
PART_NUMBER"CH4104K1B00"
VALUE"0.1UF"
TOLERANCE"10%"
MATERIAL"X7R"
BOM_COST"OCP3.0 "
CDS_LIB"pure_quanta";
"B"
$PN"2"14;
"A"
$PN"1"29;
%"UNIVERSAL_GND"
"1","(-7900,750)","0","pure_quanta_power","I32";
;
HDL_POWER"GND"
CDS_LIB"pure_quanta_power"
BOM_COST"OCP3.0 ";
"A"14;
%"UNIVERSAL_GND"
"1","(-7550,400)","0","pure_quanta_power","I36";
;
HDL_POWER"GND"
BOM_COST"OCP3.0 "
CDS_LIB"pure_quanta_power";
"A"15;
%"UNIVERSAL_POWER"
"1","(-2975,3200)","0","pure_quanta_power","I37";
;
HDL_POWER"P3V3_STBY"
CDS_LIB"pure_quanta_power";
"A"16;
%"Q_RES"
"2","(-2975,2925)","0","pure_quanta","I39";
;
LOCATION"R1367"
$SEC"1"
CDS_SEC"1"
PACK_TYPE"0402LF"
VALUE"1K"
TOLERANCE"5%"
MATERIAL"CHIP"
WATTAGE"1/16W"
PART_NUMBER"TMP_QCS21002JB34"
CDS_LIB"pure_quanta";
"A"
$PN"1"16;
"B"
$PN"2"58;
%"MOSFET_N_GSD"
"1","(-3000,2500)","0","pure_quanta","I40";
;
LOCATION"Q13"
$SEC"1"
CDS_SEC"1"
PART_NUMBER"BAM01380023"
VALUE"NX138BK"
MATERIAL"IC"
PART_TYPE"SMLF"
NEEDS_NO_SIZE"TRUE"
CDS_LMAN_SYM_OUTLINE"-100,100,100,-100"
CDS_LIB"pure_quanta";
"DRAIN"
$PN"D"58;
"SOURCE"
$PN"S"30;
"GATE"
$PN"G"57;
%"Q_RES"
"1","(-3350,2225)","1","pure_quanta","I41";
;
LOCATION"R1366"
$SEC"1"
CDS_SEC"1"
PACK_TYPE"0402LF"
VALUE"100K"
TOLERANCE"1%"
MATERIAL"CHIP"
WATTAGE"1/16W"
PART_NUMBER"TMP_QCS41002FB28"
CDS_LIB"pure_quanta";
"B"
$PN"2"57;
"A"
$PN"1"30;
%"Q_RES"
"2","(-2950,1525)","0","pure_quanta","I45";
;
LOCATION"R1368"
$SEC"1"
CDS_SEC"1"
PACK_TYPE"0402LF"
VALUE"1K"
TOLERANCE"5%"
MATERIAL"CHIP"
WATTAGE"1/16W"
PART_NUMBER"TMP_QCS21002JB34"
CDS_LIB"pure_quanta";
"A"
$PN"1"4;
"B"
$PN"2"56;
%"UNIVERSAL_GND"
"1","(-3350,1975)","0","pure_quanta_power","I46";
;
HDL_POWER"GND"
CDS_LIB"pure_quanta_power";
"A"30;
%"MOSFET_N_GSD"
"1","(-2975,1100)","0","pure_quanta","I47";
;
LOCATION"Q14"
$SEC"1"
CDS_SEC"1"
PART_NUMBER"BAM01380023"
VALUE"NX138BK"
MATERIAL"IC"
PART_TYPE"SMLF"
CDS_LIB"pure_quanta"
CDS_LMAN_SYM_OUTLINE"-100,100,100,-100"
NEEDS_NO_SIZE"TRUE";
"DRAIN"
$PN"D"56;
"SOURCE"
$PN"S"31;
"GATE"
$PN"G"55;
%"Q_RES"
"1","(-3325,825)","1","pure_quanta","I48";
;
LOCATION"R1193"
$SEC"1"
CDS_SEC"1"
PACK_TYPE"0402LF"
VALUE"100K"
TOLERANCE"1%"
MATERIAL"CHIP"
WATTAGE"1/16W"
PART_NUMBER"TMP_QCS41002FB28"
CDS_LIB"pure_quanta";
"B"
$PN"2"55;
"A"
$PN"1"31;
%"UNIVERSAL_GND"
"1","(-3325,575)","0","pure_quanta_power","I49";
;
HDL_POWER"GND"
CDS_LIB"pure_quanta_power";
"A"31;
%"VCC_CORE"
"1","(-6200,6350)","0","pure_quanta_power","I51";
;
HDL_POWER"P3V3_STBY"
CDS_LIB"pure_quanta_power";
"A"17;
%"Q_RES"
"2","(-6200,6050)","0","pure_quanta","I52";
;
LOCATION"R673"
$SEC"1"
CDS_SEC"1"
PACK_TYPE"0402LF"
PART_NUMBER"TMP_QCS21002JB34"
VALUE"1K"
TOLERANCE"5%"
MATERIAL"CHIP"
WATTAGE"1/16W"
CDS_LIB"pure_quanta";
"A"
$PN"1"17;
"B"
$PN"2"53;
%"Q_RES"
"1","(-6550,5725)","2","pure_quanta","I55";
;
LOCATION"R672"
$SEC"1"
CDS_SEC"1"
VALUE"33"
PACK_TYPE"0402LF"
PART_NUMBER"CS03302JB29"
TOLERANCE"5%"
MATERIAL"CHIP"
WATTAGE"1/16W"
CDS_LIB"pure_quanta";
"B"
$PN"2"50;
"A"
$PN"1"53;
%"VCC_CORE"
"1","(-8650,6200)","0","pure_quanta_power","I59";
;
HDL_POWER"P3V3_STBY"
CDS_LIB"pure_quanta_power";
"A"18;
%"GND"
"1","(-7175,5825)","1","pure_quanta_power","I60";
;
HDL_POWER"GND"
BOM_COST"MEM"
SIZE"1B"
CDS_LIB"pure_quanta_power";
"A<SIZE-1..0>\NAC"19;
%"MOSFET_DUAL_6P"
"1","(-7575,5775)","0","pure_quanta","I61";
;
LOCATION"Q6"
$SEC"1"
CDS_SEC"1"
PART_NUMBER"BAM70020047"
VALUE"2N7002KDW"
MATERIAL"IC"
PART_TYPE"SMLF"
CDS_LIB"pure_quanta"
CDS_LMAN_SYM_OUTLINE"-150,100,150,-100"
NEEDS_NO_SIZE"TRUE";
"D2"
$PN"3"50;
"D1"
$PN"6"36;
"S2"
$PN"4"19;
"S1"
$PN"1"20;
"G2"
$PN"5"51;
"G1"
$PN"2"49;
%"GND"
"1","(-8050,5825)","7","pure_quanta_power","I62";
;
HDL_POWER"GND"
BOM_COST"MEM"
SIZE"1B"
CDS_LIB"pure_quanta_power";
"A<SIZE-1..0>\NAC"20;
%"Q_RES"
"2","(-7950,5550)","2","pure_quanta","I63";
;
LOCATION"R1308"
$SEC"1"
CDS_SEC"1"
PACK_TYPE"0402LF"
PART_NUMBER"TMP_QCS24702JB38"
VALUE"4.7K"
TOLERANCE"5%"
MATERIAL"CHIP"
WATTAGE"1/16W"
CDS_LIB"pure_quanta";
"A"
$PN"1"49;
"B"
$PN"2"21;
%"GND"
"1","(-7950,5325)","0","pure_quanta_power","I64";
;
HDL_POWER"GND"
SIZE"1B"
BOM_COST"MEM"
CDS_LIB"pure_quanta_power";
"A<SIZE-1..0>\NAC"21;
%"SN74LVC1G07DBVR"
"1","(-7175,4300)","0","pure_quanta","I65";
;
LOCATION"U92"
$SEC"1"
CDS_SEC"1"
PACK_TYPE"SMLF"
PART_NUMBER"AL1G0007024"
VALUE"SN74LVC1G07DBVR"
MATERIAL"IC"
NEEDS_NO_SIZE"TRUE"
CDS_LIB"pure_quanta";
"NC"
$PN"1"0;
"Y"
$PN"4"52;
"GND"
$PN"3"22;
"A"
$PN"2"48;
"VCC"
$PN"5"32;
%"UNIVERSAL_GND"
"1","(-7425,4025)","0","pure_quanta_power","I66";
;
HDL_POWER"GND"
BOM_COST"OCP3.0 "
CDS_LIB"pure_quanta_power";
"A"22;
%"Q_RES"
"2","(-8650,5975)","0","pure_quanta","I67";
;
LOCATION"R755"
$SEC"1"
CDS_SEC"1"
PACK_TYPE"0402LF"
PART_NUMBER"TMP_QCS24702JB38"
VALUE"4.7K"
TOLERANCE"5%"
MATERIAL"CHIP"
WATTAGE"1/16W"
CDS_LIB"pure_quanta";
"A"
$PN"1"18;
"B"
$PN"2"36;
%"UNIVERSAL_POWER"
"1","(-7775,4925)","0","pure_quanta_power","I68";
;
HDL_POWER"P1V8_STBY"
BOM_COST"OCP3.0 "
CDS_LIB"pure_quanta_power";
"A"32;
%"UNIVERSAL_GND"
"1","(-7775,4425)","0","pure_quanta_power","I71";
;
HDL_POWER"GND"
BOM_COST"OCP3.0 "
CDS_LIB"pure_quanta_power";
"A"23;
%"Q_CAP"
"1","(-7775,4625)","0","pure_quanta","I72";
;
LOCATION"C552"
$SEC"1"
CDS_SEC"1"
PACK_TYPE"0402"
VOLTAGE"25V"
PART_NUMBER"CH4104K1B00"
VALUE"0.1UF"
TOLERANCE"10%"
MATERIAL"X7R"
BOM_COST"OCP3.0 "
CDS_LIB"pure_quanta";
"B"
$PN"2"23;
"A"
$PN"1"32;
%"Q_RES"
"2","(-7900,4625)","2","pure_quanta","I73";
;
LOCATION"R996"
$SEC"1"
CDS_SEC"1"
PACK_TYPE"0402LF"
PART_NUMBER"TMP_QCS24702JB38"
VALUE"4.7K"
TOLERANCE"5%"
MATERIAL"CHIP"
WATTAGE"1/16W"
BOM_COST"OCP3.0 "
CDS_LIB"pure_quanta";
"A"
$PN"1"32;
"B"
$PN"2"48;
%"SN74LVC1G07DBVR"
"1","(-7225,2975)","0","pure_quanta","I83";
;
LOCATION"U110"
$SEC"1"
CDS_SEC"1"
PACK_TYPE"SMLF"
PART_NUMBER"AL1G0007024"
VALUE"SN74LVC1G07DBVR"
MATERIAL"IC"
CDS_LIB"pure_quanta"
NEEDS_NO_SIZE"TRUE";
"NC"
$PN"1"0;
"Y"
$PN"4"40;
"GND"
$PN"3"25;
"A"
$PN"2"37;
"VCC"
$PN"5"33;
%"UNIVERSAL_POWER"
"1","(-7825,3600)","0","pure_quanta_power","I84";
;
HDL_POWER"P1V8_STBY"
BOM_COST"OCP3.0 "
CDS_LIB"pure_quanta_power";
"A"33;
%"Q_CAP"
"1","(-7825,3300)","0","pure_quanta","I85";
;
LOCATION"C68"
$SEC"1"
CDS_SEC"1"
PACK_TYPE"0402"
VOLTAGE"25V"
PART_NUMBER"CH4104K1B00"
VALUE"0.1UF"
TOLERANCE"10%"
MATERIAL"X7R"
CDS_LIB"pure_quanta"
BOM_COST"OCP3.0 ";
"B"
$PN"2"24;
"A"
$PN"1"33;
%"UNIVERSAL_GND"
"1","(-7825,3100)","0","pure_quanta_power","I86";
;
HDL_POWER"GND"
BOM_COST"OCP3.0 "
CDS_LIB"pure_quanta_power";
"A"24;
%"Q_RES"
"2","(-7950,3300)","2","pure_quanta","I87";
;
LOCATION"R419"
$SEC"1"
CDS_SEC"1"
PACK_TYPE"0402LF"
PART_NUMBER"TMP_QCS24702JB38"
VALUE"4.7K"
TOLERANCE"5%"
MATERIAL"CHIP"
WATTAGE"1/16W"
CDS_LIB"pure_quanta"
BOM_COST"OCP3.0 ";
"A"
$PN"1"33;
"B"
$PN"2"37;
%"UNIVERSAL_GND"
"1","(-7475,2700)","0","pure_quanta_power","I88";
;
HDL_POWER"GND"
BOM_COST"OCP3.0 "
CDS_LIB"pure_quanta_power";
"A"25;
%"Q_RES"
"1","(-6025,2925)","0","pure_quanta","I96";
;
LOCATION"R1399"
$SEC"1"
CDS_SEC"1"
VALUE"0"
PACK_TYPE"0402LF"
PART_NUMBER"CS00002JB38"
TOLERANCE"5%"
MATERIAL"CHIP"
WATTAGE"1/16W"
CDS_LIB"pure_quanta"
BOM_COST"OCP3.0 ";
"B"
$PN"2"44;
"A"
$PN"1"40;
%"Q_RES"
"1","(-6025,2875)","0","pure_quanta","I97";
;
LOCATION"R1400"
$SEC"1"
CDS_SEC"1"
VALUE"0"
PACK_TYPE"0402LF"
PART_NUMBER"CS00002JB38"
TOLERANCE"5%"
MATERIAL"CHIP"
WATTAGE"1/16W"
CDS_LIB"pure_quanta"
BOM_COST"OCP3.0 ";
"B"
$PN"2"45;
"A"
$PN"1"40;
%"Q_RES"
"1","(-6025,2825)","0","pure_quanta","I98";
;
LOCATION"R1401"
$SEC"1"
CDS_SEC"1"
VALUE"0"
PACK_TYPE"0402LF"
PART_NUMBER"CS00002JB38"
TOLERANCE"5%"
MATERIAL"CHIP"
WATTAGE"1/16W"
CDS_LIB"pure_quanta"
BOM_COST"OCP3.0 ";
"B"
$PN"2"47;
"A"
$PN"1"40;
%"Q_RES"
"1","(-6025,2775)","0","pure_quanta","I99";
;
LOCATION"R1402"
$SEC"1"
CDS_SEC"1"
VALUE"0"
PACK_TYPE"0402LF"
PART_NUMBER"CS00002JB38"
TOLERANCE"5%"
MATERIAL"CHIP"
WATTAGE"1/16W"
CDS_LIB"pure_quanta"
BOM_COST"OCP3.0 ";
"B"
$PN"2"46;
"A"
$PN"1"40;
END.
